# T6G (Grand Teton) — schematic parts with pin connectivity, parts 4197–4354 of 8303; source: Cadence DE-HDL packaged netlist (pstxprt.dat, pstxnet.dat, pstchip.dat)

PR423  Q_RES  8.87K 1% EMPTY  pkg 0402LF  page 213 : 1 = GND ; 2 = PVDDCR_CPU0_P1_LSET6
PR424  Q_RES  5.6 1% CHIP  pkg 0402LF  page 213 : 1 = SW_PVDDCR_CPU0_P1_BOOT6 ; 2 = SW_PVDDCR_CPU0_P1_BOOT6_RC
PR425  Q_RES  0 5% CHIP  pkg 0402LF  page 213 : 1 = PVDDCR_CPU0_P1_VOS6 ; 2 = PVDDCR_CPU0_P1
PR426  Q_RES  8.87K 1% EMPTY  pkg 0402LF  page 220 : 1 = PVDDCR_CPU1_P1_LSET6 ; 2 = GND
PR427  Q_RES  2.2 1% CHIP  pkg 0402LF  page 220 : 1 = PVDDCR_CPU1_P1_PVCC ; 2 = PVDDCR_CPU1_P1_VCC6
PR428  Q_RES  5.6 1% CHIP  pkg 0402LF  page 220 : 1 = SW_PVDDCR_CPU1_P1_BOOT6 ; 2 = SW_PVDDCR_CPU1_P1_BOOT6_R
PR429  Q_RES  0 5% CHIP  pkg 0402LF  page 220 : 1 = PVDDCR_CPU1_P1_VOS6 ; 2 = PVDDCR_CPU1_P1
PR430  Q_RES  2.2 1% CHIP  pkg 0402LF  page 196 : 1 = PVDDCR_CPU0_P0_PVCC ; 2 = PVDDCR_CPU0_P0_VCC6
PR431  Q_RES  8.87K 1% EMPTY  pkg 0402LF  page 196 : 1 = GND ; 2 = PVDDCR_CPU0_P0_LSET6
PR432  Q_RES  5.6 1% CHIP  pkg 0402LF  page 196 : 1 = SW_PVDDCR_CPU0_P0_BOOT6 ; 2 = SW_PVDDCR_CPU0_P0_BOOT6_RC
PR433  Q_RES  0 5% CHIP  pkg 0402LF  page 196 : 1 = PVDDCR_CPU0_P0_VOS6 ; 2 = PVDDCR_CPU0_P0
PR434  Q_RES  10 1% CHIP  pkg 0402LF  page 209 : 1 = PVDD18_S5_P0_FB_RC ; 2 = VSENSE_PVDD18_S5_P0_DP
PR435  Q_RES  0 5% CHIP  pkg 0402LF  page 209 : 1 = PVDD18_S5_P0_RGND ; 2 = VSENSE_PVDD18_S5_P0_DN
PR436  Q_RES  0 5% CHIP  pkg 0402LF  page 210 : 1 = NC_PVDDCR_CPU0_P1_IMON8 ; 2 = GND
PR437  Q_RES  0 5% CHIP  pkg 0402LF  page 210 : 1 = NC_PVDDCR_CPU0_P1_IMON9 ; 2 = GND
PR438  Q_RES  49.9 1% CHIP  pkg 0402LF  page 209 : 1 = PVDD18_S5_P0_FB_RC ; 2 = PVDD18_S5_P0
PR439  Q_RES  1K 1% CHIP  pkg 0402LF  page 209 : 1 = PVDD18_S5_P0 ; 2 = GND
PR440  Q_RES  0 5% CHIP  pkg 0402LF  page 193 : 1 = NC_PVDDCR_CPU0_P0_IMON8 ; 2 = GND
PR441  Q_RES  0 5% CHIP  pkg 0402LF  page 193 : 1 = NC_PVDDCR_CPU0_P0_IMON9 ; 2 = GND
PR442  Q_RES  0 5% CHIP  pkg 0402LF  page 201 : 1 = PVDDCR_CPU1_P0_PVCC ; 2 = P5V_AUX
PR443  Q_RES  0 5% EMPTY  pkg 0402LF  page 201 : 1 = PVDDCR_CPU1_P0_PVCC ; 2 = P3V3_AUX
PR444  Q_RES  1K 1% CHIP  pkg 0402LF  page 201 : 1 = PVDDCR_CPU1_P0 ; 2 = GND
PR445  Q_RES  0 5% CHIP  pkg 0402LF  page 194 : 1 = PVDDCR_CPU0_P0_PVCC ; 2 = P5V_AUX
PR446  Q_RES  0 5% EMPTY  pkg 0402LF  page 194 : 1 = PVDDCR_CPU0_P0_PVCC ; 2 = P3V3_AUX
PR447  Q_RES  1K 1% CHIP  pkg 0402LF  page 194 : 1 = PVDDCR_CPU0_P0 ; 2 = GND
PR448  Q_RES  8.66K 1% CHIP  pkg 0402LF  page 209 : 1 = PVDD18_S5_P0_CS ; 2 = GND
PR452  Q_RES  6.98K 1% CHIP  pkg 0402LF  page 192 : 1 = PVDD_33_S5_CS ; 2 = GND
PR454  Q_RES  12.4K 1% CHIP  pkg 0402LF  page 192 : 1 = PVDD_33_S5_FB ; 2 = GND
PR455  Q_RES  56K 1% CHIP  pkg 0402LF  page 192 : 1 = PVDD_33_S5_FB ; 2 = PVDD_33_S5
PR460  Q_RES  49.9 1% CHIP  pkg 0402LF  page 217 : 1 = VSENSE_VSS_SENSE_B_P1 ; 2 = GND
PR464  Q_RES  13.7K 1% CHIP  pkg 0402LF  page 224 : 1 = GND ; 2 = PVDD11_S3_P1_ADDR_CFG
PR470  Q_RES  10K 1% CHIP  pkg 0402LF  page 209 : 1 = PVDD18_S5_P0_FB ; 2 = PVDD18_S5_P0_RGND
PR471  Q_RES  20K 1% CHIP  pkg 0402LF  page 209 : 1 = PVDD18_S5_P0_FB ; 2 = PVDD18_S5_P0_FB_RC
PR477  Q_RES  0 5% CHIP  pkg 0402LF  page 209 : 1 = P3V3_AUX ; 2 = PVDD18_S5_P0_VCC
PR482  Q_RES  1.5 1% EMPTY  pkg 0402LF  page 208 : 1 = SW_PVDD11_S3_P0_SW1_RC ; 2 = GND
PR485  Q_RES  1.5 1% EMPTY  pkg 0402LF  page 211 : 1 = SW_PVDDCR_CPU0_P1_SW1_RC ; 2 = GND
PR486  Q_RES  1.5 1% EMPTY  pkg 0402LF  page 211 : 1 = SW_PVDDCR_CPU0_P1_SW2_RC ; 2 = GND
PR488  Q_RES  1.5 1% EMPTY  pkg 0402LF  page 222 : 1 = SW_PVDDIO_P1_SW1_RC ; 2 = GND
PR489  Q_RES  1.5 1% EMPTY  pkg 0402LF  page 222 : 1 = SW_PVDDIO_P1_SW2_RC ; 2 = GND
PR491  Q_RES  1.5 1% EMPTY  pkg 0402LF  page 223 : 1 = SW_PVDDIO_P1_SW4_RC ; 2 = GND
PR492  Q_RES  1.5 1% EMPTY  pkg 0402LF  page 223 : 1 = SW_PVDDIO_P1_SW3_RC ; 2 = GND
PR495  Q_RES  1.5 1% EMPTY  pkg 0402LF  page 194 : 1 = SW_PVDDCR_CPU0_P0_SW1_RC ; 2 = GND
PR496  Q_RES  1.5 1% EMPTY  pkg 0402LF  page 194 : 1 = SW_PVDDCR_CPU0_P0_SW2_RC ; 2 = GND
PR498  Q_RES  1.5 1% EMPTY  pkg 0402LF  page 195 : 1 = SW_PVDDCR_CPU0_P0_SW3_RC ; 2 = GND
PR499  Q_RES  1.5 1% EMPTY  pkg 0402LF  page 195 : 1 = SW_PVDDCR_CPU0_P0_SW4_RC ; 2 = GND
PR500  Q_RES  1.5 1% EMPTY  pkg 0402LF  page 196 : 1 = SW_PVDDCR_CPU0_P0_SW6_RC ; 2 = GND
PR501  Q_RES  1.5 1% EMPTY  pkg 0402LF  page 196 : 1 = SW_PVDDCR_CPU0_P0_SW5_RC ; 2 = GND
PR502  Q_RES  1.5 1% EMPTY  pkg 0402LF  page 198 : 1 = SW_PVDDCR_SOC_P0_SW1_RC ; 2 = GND
PR503  Q_RES  1.5 1% EMPTY  pkg 0402LF  page 198 : 1 = SW_PVDDCR_SOC_P0_SW2_RC ; 2 = GND
PR505  Q_RES  1.5 1% EMPTY  pkg 0402LF  page 199 : 1 = SW_PVDDCR_SOC_P0_SW3_RC ; 2 = GND
PR506  Q_RES  1.5 1% EMPTY  pkg 0402LF  page 201 : 1 = SW_PVDDCR_CPU1_P0_SW1_RC ; 2 = GND
PR507  Q_RES  1.5 1% EMPTY  pkg 0402LF  page 201 : 1 = SW_PVDDCR_CPU1_P0_SW2_RC ; 2 = GND
PR509  Q_RES  1.5 1% EMPTY  pkg 0402LF  page 202 : 1 = SW_PVDDCR_CPU1_P0_SW4_RC ; 2 = GND
PR510  Q_RES  1.5 1% EMPTY  pkg 0402LF  page 202 : 1 = SW_PVDDCR_CPU1_P0_SW3_RC ; 2 = GND
PR511  Q_RES  1.5 1% EMPTY  pkg 0402LF  page 216 : 1 = SW_PVDDCR_SOC_P1_SW3_RC ; 2 = GND
PR512  Q_RES  1.5 1% EMPTY  pkg 0402LF  page 218 : 1 = SW_PVDDCR_CPU1_P1_SW1_RC ; 2 = GND
PR513  Q_RES  1.5 1% EMPTY  pkg 0402LF  page 218 : 1 = SW_PVDDCR_CPU1_P1_SW2_RC ; 2 = GND
PR515  Q_RES  1.5 1% EMPTY  pkg 0402LF  page 219 : 1 = SW_PVDDCR_CPU1_P1_SW4_RC ; 2 = GND
PR516  Q_RES  1.5 1% EMPTY  pkg 0402LF  page 219 : 1 = SW_PVDDCR_CPU1_P1_SW3_RC ; 2 = GND
PR517  Q_RES  1.5 1% EMPTY  pkg 0402LF  page 220 : 1 = SW_PVDDCR_CPU1_P1_SW5_RC ; 2 = GND
PR518  Q_RES  1.5 1% EMPTY  pkg 0402LF  page 220 : 1 = SW_PVDDCR_CPU1_P1_SW6_RC ; 2 = GND
PR519  Q_RES  1.5 1% EMPTY  pkg 0402LF  page 225 : 1 = SW_PVDD11_S3_P1_SW2_RC ; 2 = GND
PR520  Q_RES  1.5 1% EMPTY  pkg 0402LF  page 225 : 1 = SW_PVDD11_S3_P1_SW1_RC ; 2 = GND
PR522  Q_RES  1.5 1% EMPTY  pkg 0402LF  page 212 : 1 = SW_PVDDCR_CPU0_P1_SW3_RC ; 2 = GND
PR523  Q_RES  1.5 1% EMPTY  pkg 0402LF  page 212 : 1 = SW_PVDDCR_CPU0_P1_SW4_RC ; 2 = GND
PR524  Q_RES  1.5 1% EMPTY  pkg 0402LF  page 213 : 1 = SW_PVDDCR_CPU0_P1_SW6_RC ; 2 = GND
PR525  Q_RES  1.5 1% EMPTY  pkg 0402LF  page 215 : 1 = SW_PVDDCR_SOC_P1_SW1_RC ; 2 = GND
PR526  Q_RES  1.5 1% EMPTY  pkg 0402LF  page 215 : 1 = SW_PVDDCR_SOC_P1_SW2_RC ; 2 = GND
PR530  Q_RES  0 5% CHIP  pkg 0402LF  page 210 : 1 = NC_PVDDCR_CPU0_P1_IMON7 ; 2 = GND
PR531  Q_RES  0 5% CHIP  pkg 0402LF  page 193 : 1 = NC_PVDDCR_CPU0_P0_IMON7 ; 2 = GND
PR532  Q_RES  0 5% CHIP  pkg 0402LF  page 200 : 1 = NC_PVDDCR_CPU1_P0_IMON7 ; 2 = GND
PR533  Q_RES  0 5% CHIP  pkg 0402LF  page 217 : 1 = NC_PVDDCR_CPU1_P1_IMON7 ; 2 = GND
PR599  Q_RES  4.99K 1% EMPTY  pkg 0402LF  page 193 : 1 = PVDDCR_CPU0_P0_VINSEN ; 2 = GND
PR600  Q_RES  4.99K 1% EMPTY  pkg 0402LF  page 200 : 1 = PVDDCR_CPU1_P0_VINSEN ; 2 = GND
PR601  Q_RES  4.99K 1% EMPTY  pkg 0402LF  page 207 : 1 = PVDD11_S3_P0_VINSEN ; 2 = GND
PR602  Q_RES  4.99K 1% EMPTY  pkg 0402LF  page 210 : 1 = PVDDCR_CPU0_P1_VINSEN ; 2 = GND
PR603  Q_RES  4.99K 1% EMPTY  pkg 0402LF  page 217 : 1 = PVDDCR_CPU1_P1_VINSEN ; 2 = GND
PR604  Q_RES  4.99K 1% EMPTY  pkg 0402LF  page 224 : 1 = PVDD11_S3_P1_VINSEN ; 2 = GND
PR830  Q_RES  15K 0.1% CHIP  pkg 0402LF  page 190 : 1 = P3V3_AUX_FB ; 2 = GND
PR831  Q_RES  47K 0.1% CHIP  pkg 0402LF  page 190 : 1 = P3V3_AUX_FB ; 2 = P3V3_AUX
PR832  Q_RES  0 5% CHIP  pkg 0402LF  page 190 : 1 = P3V3_AUX_MODE ; 2 = GND
PR833  Q_RES  1.5K 1% EMPTY  pkg 0402LF  page 190 : 1 = P3V3_AUX_SS ; 2 = GND
PR834  Q_RES  21.5K 1% CHIP  pkg 0402LF  page 190 : 1 = P3V3_AUX_ILIM ; 2 = GND
PR835  Q_RES  0 5% CHIP  pkg 0402LF  page 190 : 1 = SW_P3V3_AUX_BOOT ; 2 = SW_P3V3_AUX_BOOT_R
PR836  Q_RES  1K 1% CHIP  pkg 0402LF  page 190 : 1 = P3V3_AUX_VOS ; 2 = P3V3_AUX
PR883  Q_RES  0 5% EMPTY  pkg 0402LF  page 362 : 1 = TP_P0V9_RETIMER_CPU0_SVID_ALERT_N ; 2 = GND
PR885  Q_RES  5.36K 1% EMPTY  pkg 0402LF  page 364 : 1 = P5V_AUX ; 2 = P0V9_RETIMER_CPU1_VMON
PR1101  Q_RES  2K 0.1% CHIP  pkg 0402LF  page 263 : 1 = HSC_IMON ; 2 = AGND_HSC
PR1131  Q_RES  2K 0.1% CHIP  pkg 0402LF  page 262 : 1 = HSC_CS ; 2 = AGND_HSC
PR1133  Q_RES  2K 0.1% CHIP  pkg 0402LF  page 262 : 1 = HSC_IMON ; 2 = AGND_HSC
PR1134  Q_RES  120K 1% CHIP  pkg 0402LF  page 263 : 1 = AGND_HSC ; 2 = HSC_MODE_1
PR2106  Q_RES  10K 1% CHIP  pkg 0402LF  page 262 : 1 = HSC_VDD ; 2 = HSC_VIN_UVW_N
PR2149  Q_RES  0 5% CHIP  pkg 0402LF  page 262 : 1 = HSC_VDD_R ; 2 = HSC_VDD
PR2510  Q_RES  1 1% CHIP  pkg 0402LF  page 266 : 1 = P12V_HSC_ADC_P ; 2 = P12V_HSC_SENSE2_R1_P
PR2511  Q_RES  1 1% CHIP  pkg 0402LF  page 266 : 1 = P12V_HSC_ADC_P ; 2 = P12V_HSC_SENSE2_R2_P
PR2512  Q_RES  1 1% CHIP  pkg 0402LF  page 266 : 1 = P12V_HSC_ADC_P ; 2 = P12V_HSC_SENSE2_R3_P
PR2513  Q_RES  1 1% CHIP  pkg 0402LF  page 266 : 1 = P12V_HSC_ADC_P ; 2 = P12V_HSC_SENSE2_R4_P
PR2514  Q_RES  10 1% CHIP  pkg 0402LF  page 266 : 1 = P12V_HSC_ADC_P ; 2 = P12V_HSC_SENSE1_P
PR2515  Q_RES  10 1% CHIP  pkg 0402LF  page 266 : 1 = P12V_HSC_ADC_N ; 2 = P12V_HSC_SENSE2_R1_N
PR2516  Q_RES  10 1% CHIP  pkg 0402LF  page 266 : 1 = P12V_HSC_ADC_N ; 2 = P12V_HSC_SENSE2_R2_N
PR2517  Q_RES  10 1% CHIP  pkg 0402LF  page 266 : 1 = P12V_HSC_ADC_N ; 2 = P12V_HSC_SENSE2_R3_N
PR2518  Q_RES  10 1% CHIP  pkg 0402LF  page 266 : 1 = P12V_HSC_ADC_N ; 2 = P12V_HSC_SENSE2_R4_N
PR2519  Q_RES  100 1% CHIP  pkg 0402LF  page 266 : 1 = P12V_HSC_ADC_N ; 2 = P12V_HSC_SENSE1_N
PR2520  Q_RES  1 1% CHIP  pkg 0402LF  page 266 : 1 = P12V_HSC_SENSE2_P ; 2 = P12V_HSC_SENSE2_R1_P
PR2521  Q_RES  1 1% CHIP  pkg 0402LF  page 266 : 1 = P12V_HSC_SENSE2_P ; 2 = P12V_HSC_SENSE2_R2_P
PR2522  Q_RES  1 1% CHIP  pkg 0402LF  page 266 : 1 = P12V_HSC_SENSE2_P ; 2 = P12V_HSC_SENSE2_R3_P
PR2523  Q_RES  1 1% CHIP  pkg 0402LF  page 266 : 1 = P12V_HSC_SENSE2_P ; 2 = P12V_HSC_SENSE2_R4_P
PR2524  Q_RES  10 1% CHIP  pkg 0402LF  page 266 : 1 = P12V_HSC_SENSE2_N ; 2 = P12V_HSC_SENSE2_R1_N
PR2525  Q_RES  10 1% CHIP  pkg 0402LF  page 266 : 1 = P12V_HSC_SENSE2_N ; 2 = P12V_HSC_SENSE2_R2_N
PR2526  Q_RES  10 1% CHIP  pkg 0402LF  page 266 : 1 = P12V_HSC_SENSE2_N ; 2 = P12V_HSC_SENSE2_R3_N
PR2527  Q_RES  10 1% CHIP  pkg 0402LF  page 266 : 1 = P12V_HSC_SENSE2_N ; 2 = P12V_HSC_SENSE2_R4_N
PR2528  Q_RES  10 1% CHIP  pkg 0402LF  page 266 : 1 = P12V_HSC_GATE_G1 ; 2 = P12V_HSC_GATE2
PR2529  Q_RES  10 1% CHIP  pkg 0402LF  page 266 : 1 = P12V_HSC_GATE_G2 ; 2 = P12V_HSC_GATE2
PR2530  Q_RES  10 1% CHIP  pkg 0402LF  page 266 : 1 = P12V_HSC_GATE_G3 ; 2 = P12V_HSC_GATE2
PR2531  Q_RES  10 1% CHIP  pkg 0402LF  page 266 : 1 = P12V_HSC_GATE_G4 ; 2 = P12V_HSC_GATE2

PR2532  Q_SP_RES4P  0.0003 1% CHIP  pkg R2725_4P  page 266
  1A  \1a\  BI  = P12V_PSU
  1B  \1b\  BI  = P12V_HSC_SENSE2_R2_P
  2A  \2a\  BI  = P12V_MAIN_R
  2B  \2b\  BI  = P12V_HSC_SENSE2_R2_N

PR2533  Q_SP_RES4P  0.0003 1% CHIP  pkg R2725_4P  page 266
  1A  \1a\  BI  = P12V_PSU
  1B  \1b\  BI  = P12V_HSC_SENSE2_R3_P
  2A  \2a\  BI  = P12V_MAIN_R
  2B  \2b\  BI  = P12V_HSC_SENSE2_R3_N

PR2534  Q_SP_RES4P  0.0003 1% CHIP  pkg R2725_4P  page 266
  1A  \1a\  BI  = P12V_PSU
  1B  \1b\  BI  = P12V_HSC_SENSE2_R4_P
  2A  \2a\  BI  = P12V_MAIN_R
  2B  \2b\  BI  = P12V_HSC_SENSE2_R4_N

PR2535  Q_RES  10 1% CHIP  pkg 0402LF  page 266 : 1 = P12V_HSC_GATE_G5 ; 2 = P12V_HSC_GATE2
PR2536  Q_RES  10 1% CHIP  pkg 0402LF  page 266 : 1 = P12V_HSC_GATE_G6 ; 2 = P12V_HSC_GATE2
PR2537  Q_RES  10 1% EMPTY  pkg 0402LF  page 266 : 1 = P12V_AUX ; 2 = P12V_HSC_GATE_RC
PR2538  Q_RES  10 1% CHIP  pkg 0402LF  page 266 : 1 = MB0_CM_GATE_G0 ; 2 = P12V_HSC_GATE1
PR3002  Q_RES  0 5% CHIP  pkg 0402LF  page 268 : 1 = GND ; 2 = AGND_HSC
PR3337  Q_RES  0 5% CHIP  pkg 0402LF  page 189 : 1 = P5V_AUX_MODE ; 2 = GND
PR3780  Q_RES  5.36K 1% CHIP  pkg 0402LF  page 134 : 1 = P3V3_OCP_CB_1 ; 2 = GND
PR3781  Q_RES  845 1% CHIP  pkg 0402LF  page 134 : 1 = P12V_OCP_SENSE_1 ; 2 = GND
PR3782  Q_RES  10 1% CHIP  pkg 0402LF  page 140 : 1 = P3V3_AUX ; 2 = P3V3_OCP_VCC_2
PR3786  Q_RES  160K 1% CHIP  pkg 0402LF  page 134 : 1 = P12V_AUX ; 2 = P12V_OCP_UV_1
PR3787  Q_RES  6.8K 1% CHIP  pkg 0402LF  page 134 : 1 = P12V_OCP_UV_1 ; 2 = P12V_OCP_OV_1
PR3788  Q_RES  15K 1% CHIP  pkg 0402LF  page 134 : 1 = P12V_OCP_OV_1 ; 2 = GND
PR3789  Q_RES  25.5K 1% CHIP  pkg 0402LF  page 134 : 1 = P3V3_AUX ; 2 = P3V3_OCP_UV_1
PR3790  Q_RES  7.15K 1% CHIP  pkg 0402LF  page 134 : 1 = P3V3_OCP_UV_1 ; 2 = P3V3_OCP_OV_1
PR3791  Q_RES  15K 1% CHIP  pkg 0402LF  page 134 : 1 = P3V3_OCP_OV_1 ; 2 = GND
PR3792  Q_RES  10 1% CHIP  pkg 0402LF  page 134 : 1 = P12V_AUX ; 2 = P12V_OCP_VCC_1
PR3795  Q_RES  25.5K 1% CHIP  pkg 0402LF  page 140 : 1 = P3V3_AUX ; 2 = P3V3_OCP_UV_2
PR3798  Q_RES  10 1% CHIP  pkg 0402LF  page 134 : 1 = P3V3_AUX ; 2 = P3V3_OCP_VCC_1
PR3805  Q_RES  160K 1% CHIP  pkg 0402LF  page 140 : 1 = P12V_AUX ; 2 = P12V_OCP_UV_2
PR3806  Q_RES  6.8K 1% CHIP  pkg 0402LF  page 140 : 1 = P12V_OCP_UV_2 ; 2 = P12V_OCP_OV_2
PR3812  Q_RES  15K 1% CHIP  pkg 0402LF  page 140 : 1 = P3V3_OCP_OV_2 ; 2 = GND
PR3821  Q_RES  30.1K 1% CHIP  pkg 0402LF  page 140 : 1 = P12V_OCP_CB_2 ; 2 = GND
PR3822  Q_RES  5.36K 1% CHIP  pkg 0402LF  page 140 : 1 = P3V3_OCP_CB_2 ; 2 = GND
PR3823  Q_RES  845 1% CHIP  pkg 0402LF  page 140 : 1 = P12V_OCP_SENSE_2 ; 2 = GND
PR3824  Q_RES  4.53K 1% CHIP  pkg 0402LF  page 140 : 1 = P3V3_OCP_SENSE_2 ; 2 = GND
PR3828  Q_RES  15K 1% CHIP  pkg 0402LF  page 140 : 1 = P12V_OCP_OV_2 ; 2 = GND
PR3829  Q_RES  7.15K 1% CHIP  pkg 0402LF  page 140 : 1 = P3V3_OCP_UV_2 ; 2 = P3V3_OCP_OV_2
PR3830  Q_RES  10 1% CHIP  pkg 0402LF  page 140 : 1 = P12V_AUX ; 2 = P12V_OCP_VCC_2
PR3835  Q_RES  14.3K 1% CHIP  pkg 0402LF  page 135 : 1 = P12V_OCP_ISET_1 ; 2 = GND
PR3837  Q_RES  17.4K 1% CHIP  pkg 0402LF  page 135 : 1 = P12V_OCP_IMON_1 ; 2 = GND
PR3838  Q_RES  100 1% EMPTY  pkg 0402LF  page 135 : 1 = P12V_OCP_SFF ; 2 = P12V_OCP_AVIN_PD_1
PR3839  Q_RES  10K 1% CHIP  pkg 0402LF  page 135 : 1 = P12V_OCP_FLTB_1 ; 2 = P3V3_AUX
PR3840  Q_RES  71.5K 1% EMPTY  pkg 0402LF  page 135 : 1 = P12V_OCP_SFF ; 2 = P12V_OCP_OV_FB_1
PR3841  Q_RES  120K 1% CHIP  pkg 0402LF  page 135 : 1 = P12V_AUX ; 2 = P12V_OCP_OV_FB_1
PR3842  Q_RES  10K 1% CHIP  pkg 0402LF  page 135 : 1 = P12V_OCP_OV_FB_1 ; 2 = GND
PR3843  Q_RES  49.9 1% CHIP  pkg 0603LF  page 135 : 1 = P12V_AUX ; 2 = P12V_OCP_AVIN_PD_1
PR3844  Q_RES  71.5K 1% CHIP  pkg 0402LF  page 135 : 1 = P3V3_OCP_MODE_1 ; 2 = GND
PR3846  Q_RES  1.33K 1% CHIP  pkg 0402LF  page 135 : 1 = GND ; 2 = P3V3_OCP_ILIMIT_1
PR3847  Q_RES  14.3K 1% CHIP  pkg 0402LF  page 141 : 1 = P12V_OCP_ISET_2 ; 2 = GND
PR3849  Q_RES  17.4K 1% CHIP  pkg 0402LF  page 141 : 1 = P12V_OCP_IMON_2 ; 2 = GND
